(kicad_pcb
	(version 20260206)
	(generator "pcbnew")
	(generator_version "10.0")
	(general
		(thickness 1.6)
		(legacy_teardrops no)
	)
	(paper "A4")
	(title_block
		(title "12092022_DA0F0TFB6D0_F0T_FAN_BOARD_MP5048_D_brd_v02_OCP.brd")
		(comment 1 "Grand Teton / footprints 268-273 of 924")
	)
	(layers
		(0 "F.Cu" signal "TOP")
		(4 "In1.Cu" signal "GND")
		(6 "In2.Cu" signal "IN1")
		(8 "In3.Cu" signal "IN2")
		(10 "In4.Cu" signal "GND1")
		(2 "B.Cu" signal "BOTTOM")
		(9 "F.Adhes" user "F.Adhesive")
		(11 "B.Adhes" user "B.Adhesive")
		(13 "F.Paste" user "Package Geometry/Pastemask Top")
		(15 "B.Paste" user "Package Geometry/Pastemask Bottom")
		(5 "F.SilkS" user "Ref Des/Silkscreen Top")
		(7 "B.SilkS" user "Ref Des/Silkscreen Bottom")
		(1 "F.Mask" user "Board Geometry/Soldermask Top")
		(3 "B.Mask" user "Board Geometry/Soldermask Bottom")
		(17 "Dwgs.User" user "User.Drawings")
		(19 "Cmts.User" user "User.Comments")
		(21 "Eco1.User" user "User.Eco1")
		(23 "Eco2.User" user "User.Eco2")
		(25 "Edge.Cuts" user "Board Geometry/Outline")
		(27 "Margin" user)
		(31 "F.CrtYd" user "Package Geometry/Place Bound Top")
		(29 "B.CrtYd" user "Package Geometry/Place Bound Bottom")
		(35 "F.Fab" user "Ref Des/Assembly Top")
		(33 "B.Fab" user "Ref Des/Assembly Bottom")
	)
	(footprint ""
		(layer "F.Cu")
		(at 25.019 -160.02 90)
		(property "Reference" "R4879"
			(at 0 0 90)
			(layer "F.SilkS")
			(hide yes)
			(effects
				(font
					(size 1.27 1.27)
				)
			)
		)
		(property "Value" ""
			(at 0 0 90)
			(layer "F.Fab")
			(effects
				(font
					(size 1.27 1.27)
				)
			)
		)
		(duplicate_pad_numbers_are_jumpers no)
		(fp_line
			(start 0.7874 -0.4064)
			(end 0.7874 0.4064)
			(stroke
				(width 0.1524)
				(type default)
			)
			(layer "F.SilkS")
		)
		(fp_line
			(start -0.7874 -0.4064)
			(end 0.7874 -0.4064)
			(stroke
				(width 0.1524)
				(type default)
			)
			(layer "F.SilkS")
		)
		(fp_line
			(start 0.7874 0.4064)
			(end -0.7874 0.4064)
			(stroke
				(width 0.1524)
				(type default)
			)
			(layer "F.SilkS")
		)
		(fp_line
			(start -0.7874 0.4064)
			(end -0.7874 -0.4064)
			(stroke
				(width 0.1524)
				(type default)
			)
			(layer "F.SilkS")
		)
		(fp_line
			(start -0.12065 -0.305054)
			(end -0.12065 -0.2794)
			(stroke
				(width 0.1)
				(type default)
			)
			(layer "F.Fab")
		)
		(fp_line
			(start -0.67945 -0.305054)
			(end -0.12065 -0.305054)
			(stroke
				(width 0.1)
				(type default)
			)
			(layer "F.Fab")
		)
		(fp_line
			(start 0.67945 -0.3048)
			(end 0.67945 0.3048)
			(stroke
				(width 0.1)
				(type default)
			)
			(layer "F.Fab")
		)
		(fp_line
			(start 0.12065 -0.3048)
			(end 0.67945 -0.3048)
			(stroke
				(width 0.1)
				(type default)
			)
			(layer "F.Fab")
		)
		(fp_line
			(start 0.12065 -0.2794)
			(end 0.12065 -0.3048)
			(stroke
				(width 0.1)
				(type default)
			)
			(layer "F.Fab")
		)
		(fp_line
			(start -0.12065 -0.2794)
			(end 0.12065 -0.2794)
			(stroke
				(width 0.1)
				(type default)
			)
			(layer "F.Fab")
		)
		(fp_line
			(start 0.120396 0.2794)
			(end -0.12065 0.2794)
			(stroke
				(width 0.1)
				(type default)
			)
			(layer "F.Fab")
		)
		(fp_line
			(start -0.12065 0.2794)
			(end -0.12065 0.3048)
			(stroke
				(width 0.1)
				(type default)
			)
			(layer "F.Fab")
		)
		(fp_line
			(start 0.67945 0.3048)
			(end 0.120396 0.3048)
			(stroke
				(width 0.1)
				(type default)
			)
			(layer "F.Fab")
		)
		(fp_line
			(start 0.120396 0.3048)
			(end 0.120396 0.2794)
			(stroke
				(width 0.1)
				(type default)
			)
			(layer "F.Fab")
		)
		(fp_line
			(start -0.12065 0.3048)
			(end -0.67945 0.3048)
			(stroke
				(width 0.1)
				(type default)
			)
			(layer "F.Fab")
		)
		(fp_line
			(start -0.67945 0.3048)
			(end -0.67945 -0.305054)
			(stroke
				(width 0.1)
				(type default)
			)
			(layer "F.Fab")
		)
		(pad "1" smd circle
			(at -0.40005 0 90)
			(size 0 0)
			(layers "F.Cu" "F.Mask" "F.Paste")
			(net "SMB_FAN6_R_SCL")
		)
		(pad "2" smd circle
			(at 0.40005 0 90)
			(size 0 0)
			(layers "F.Cu" "F.Mask" "F.Paste")
			(net "SMB_FAN6_SCL")
		)
	)
	(footprint ""
		(layer "F.Cu")
		(at 34.925 -297.18)
		(property "Reference" "R5526"
			(at 0 0 0)
			(layer "F.SilkS")
			(hide yes)
			(effects
				(font
					(size 1.27 1.27)
				)
			)
		)
		(property "Value" ""
			(at 0 0 0)
			(layer "F.Fab")
			(effects
				(font
					(size 1.27 1.27)
				)
			)
		)
		(duplicate_pad_numbers_are_jumpers no)
		(fp_line
			(start -0.7874 -0.4064)
			(end 0.7874 -0.4064)
			(stroke
				(width 0.1524)
				(type default)
			)
			(layer "F.SilkS")
		)
		(fp_line
			(start -0.7874 0.4064)
			(end -0.7874 -0.4064)
			(stroke
				(width 0.1524)
				(type default)
			)
			(layer "F.SilkS")
		)
		(fp_line
			(start 0.7874 -0.4064)
			(end 0.7874 0.4064)
			(stroke
				(width 0.1524)
				(type default)
			)
			(layer "F.SilkS")
		)
		(fp_line
			(start 0.7874 0.4064)
			(end -0.7874 0.4064)
			(stroke
				(width 0.1524)
				(type default)
			)
			(layer "F.SilkS")
		)
		(fp_line
			(start -0.67945 -0.305054)
			(end -0.12065 -0.305054)
			(stroke
				(width 0.1)
				(type default)
			)
			(layer "F.Fab")
		)
		(fp_line
			(start -0.67945 0.3048)
			(end -0.67945 -0.305054)
			(stroke
				(width 0.1)
				(type default)
			)
			(layer "F.Fab")
		)
		(fp_line
			(start -0.12065 -0.305054)
			(end -0.12065 -0.2794)
			(stroke
				(width 0.1)
				(type default)
			)
			(layer "F.Fab")
		)
		(fp_line
			(start -0.12065 -0.2794)
			(end 0.12065 -0.2794)
			(stroke
				(width 0.1)
				(type default)
			)
			(layer "F.Fab")
		)
		(fp_line
			(start -0.12065 0.2794)
			(end -0.12065 0.3048)
			(stroke
				(width 0.1)
				(type default)
			)
			(layer "F.Fab")
		)
		(fp_line
			(start -0.12065 0.3048)
			(end -0.67945 0.3048)
			(stroke
				(width 0.1)
				(type default)
			)
			(layer "F.Fab")
		)
		(fp_line
			(start 0.120396 0.2794)
			(end -0.12065 0.2794)
			(stroke
				(width 0.1)
				(type default)
			)
			(layer "F.Fab")
		)
		(fp_line
			(start 0.120396 0.3048)
			(end 0.120396 0.2794)
			(stroke
				(width 0.1)
				(type default)
			)
			(layer "F.Fab")
		)
		(fp_line
			(start 0.12065 -0.3048)
			(end 0.67945 -0.3048)
			(stroke
				(width 0.1)
				(type default)
			)
			(layer "F.Fab")
		)
		(fp_line
			(start 0.12065 -0.2794)
			(end 0.12065 -0.3048)
			(stroke
				(width 0.1)
				(type default)
			)
			(layer "F.Fab")
		)
		(fp_line
			(start 0.67945 -0.3048)
			(end 0.67945 0.3048)
			(stroke
				(width 0.1)
				(type default)
			)
			(layer "F.Fab")
		)
		(fp_line
			(start 0.67945 0.3048)
			(end 0.120396 0.3048)
			(stroke
				(width 0.1)
				(type default)
			)
			(layer "F.Fab")
		)
		(pad "1" smd rect
			(at -0.40005 0 180)
			(size 0.4572 0.508)
			(layers "F.Cu" "F.Mask" "F.Paste")
			(net "P12V_LED_FAN0")
		)
		(pad "2" smd rect
			(at 0.40005 0 180)
			(size 0.4572 0.508)
			(layers "F.Cu" "F.Mask" "F.Paste")
			(net "FAN_0_FAIL_LED_R_N")
		)
	)
	(footprint ""
		(layer "F.Cu")
		(at 14.351 -299.339 180)
		(property "Reference" "R5380"
			(at 0 0 180)
			(layer "F.SilkS")
			(hide yes)
			(effects
				(font
					(size 1.27 1.27)
				)
			)
		)
		(property "Value" ""
			(at 0 0 180)
			(layer "F.Fab")
			(effects
				(font
					(size 1.27 1.27)
				)
			)
		)
		(duplicate_pad_numbers_are_jumpers no)
		(fp_line
			(start 0.7874 0.4064)
			(end -0.7874 0.4064)
			(stroke
				(width 0.1524)
				(type default)
			)
			(layer "F.SilkS")
		)
		(fp_line
			(start 0.7874 -0.4064)
			(end 0.7874 0.4064)
			(stroke
				(width 0.1524)
				(type default)
			)
			(layer "F.SilkS")
		)
		(fp_line
			(start -0.7874 0.4064)
			(end -0.7874 -0.4064)
			(stroke
				(width 0.1524)
				(type default)
			)
			(layer "F.SilkS")
		)
		(fp_line
			(start -0.7874 -0.4064)
			(end 0.7874 -0.4064)
			(stroke
				(width 0.1524)
				(type default)
			)
			(layer "F.SilkS")
		)
		(fp_line
			(start 0.67945 0.3048)
			(end 0.120396 0.3048)
			(stroke
				(width 0.1)
				(type default)
			)
			(layer "F.Fab")
		)
		(fp_line
			(start 0.67945 -0.3048)
			(end 0.67945 0.3048)
			(stroke
				(width 0.1)
				(type default)
			)
			(layer "F.Fab")
		)
		(fp_line
			(start 0.12065 -0.2794)
			(end 0.12065 -0.3048)
			(stroke
				(width 0.1)
				(type default)
			)
			(layer "F.Fab")
		)
		(fp_line
			(start 0.12065 -0.3048)
			(end 0.67945 -0.3048)
			(stroke
				(width 0.1)
				(type default)
			)
			(layer "F.Fab")
		)
		(fp_line
			(start 0.120396 0.3048)
			(end 0.120396 0.2794)
			(stroke
				(width 0.1)
				(type default)
			)
			(layer "F.Fab")
		)
		(fp_line
			(start 0.120396 0.2794)
			(end -0.12065 0.2794)
			(stroke
				(width 0.1)
				(type default)
			)
			(layer "F.Fab")
		)
		(fp_line
			(start -0.12065 0.3048)
			(end -0.67945 0.3048)
			(stroke
				(width 0.1)
				(type default)
			)
			(layer "F.Fab")
		)
		(fp_line
			(start -0.12065 0.2794)
			(end -0.12065 0.3048)
			(stroke
				(width 0.1)
				(type default)
			)
			(layer "F.Fab")
		)
		(fp_line
			(start -0.12065 -0.2794)
			(end 0.12065 -0.2794)
			(stroke
				(width 0.1)
				(type default)
			)
			(layer "F.Fab")
		)
		(fp_line
			(start -0.12065 -0.305054)
			(end -0.12065 -0.2794)
			(stroke
				(width 0.1)
				(type default)
			)
			(layer "F.Fab")
		)
		(fp_line
			(start -0.67945 0.3048)
			(end -0.67945 -0.305054)
			(stroke
				(width 0.1)
				(type default)
			)
			(layer "F.Fab")
		)
		(fp_line
			(start -0.67945 -0.305054)
			(end -0.12065 -0.305054)
			(stroke
				(width 0.1)
				(type default)
			)
			(layer "F.Fab")
		)
		(pad "1" smd rect
			(at -0.40005 0)
			(size 0.4572 0.508)
			(layers "F.Cu" "F.Mask" "F.Paste")
			(net "FAN_7_OK_LED_R_N")
		)
		(pad "2" smd rect
			(at 0.40005 0)
			(size 0.4572 0.508)
			(layers "F.Cu" "F.Mask" "F.Paste")
			(net "FAN_7_OK_R_LED_N")
		)
	)
	(footprint ""
		(layer "F.Cu")
		(at 16.139922 -275.608288)
		(property "Reference" "PC54"
			(at -5.344922 6.013958 0)
			(unlocked yes)
			(layer "F.SilkS")
			(effects
				(font
					(size 0.7874 0.5842)
					(thickness 0.1524)
				)
				(justify left)
			)
		)
		(property "Value" ""
			(at 0 0 0)
			(layer "F.Fab")
			(effects
				(font
					(size 1.27 1.27)
				)
			)
		)
		(duplicate_pad_numbers_are_jumpers no)
		(fp_line
			(start -5.249926 -3.979926)
			(end -5.249926 -1.2446)
			(stroke
				(width 0.1524)
				(type default)
			)
			(layer "F.SilkS")
		)
		(fp_line
			(start -5.249926 1.2446)
			(end -5.249926 3.979926)
			(stroke
				(width 0.1524)
				(type default)
			)
			(layer "F.SilkS")
		)
		(fp_line
			(start -5.249926 3.979926)
			(end -3.979926 5.249926)
			(stroke
				(width 0.1524)
				(type default)
			)
			(layer "F.SilkS")
		)
		(fp_line
			(start -3.979926 -5.249926)
			(end -5.249926 -3.979926)
			(stroke
				(width 0.1524)
				(type default)
			)
			(layer "F.SilkS")
		)
		(fp_line
			(start -3.979926 5.249926)
			(end 5.249926 5.249926)
			(stroke
				(width 0.1524)
				(type default)
			)
			(layer "F.SilkS")
		)
		(fp_line
			(start 5.249926 -5.249926)
			(end -3.979926 -5.249926)
			(stroke
				(width 0.1524)
				(type default)
			)
			(layer "F.SilkS")
		)
		(fp_line
			(start 5.249926 -1.2446)
			(end 5.249926 -5.249926)
			(stroke
				(width 0.1524)
				(type default)
			)
			(layer "F.SilkS")
		)
		(fp_line
			(start 5.249926 5.249926)
			(end 5.249926 1.2446)
			(stroke
				(width 0.1524)
				(type default)
			)
			(layer "F.SilkS")
		)
		(fp_line
			(start -5.249926 -5.249926)
			(end -5.249926 5.249926)
			(stroke
				(width 0.1)
				(type default)
			)
			(layer "F.Fab")
		)
		(fp_line
			(start -5.249926 5.249926)
			(end 5.249926 5.249926)
			(stroke
				(width 0.1)
				(type default)
			)
			(layer "F.Fab")
		)
		(fp_line
			(start 5.249926 -5.249926)
			(end -5.249926 -5.249926)
			(stroke
				(width 0.1)
				(type default)
			)
			(layer "F.Fab")
		)
		(fp_line
			(start 5.249926 5.249926)
			(end 5.249926 -5.249926)
			(stroke
				(width 0.1)
				(type default)
			)
			(layer "F.Fab")
		)
		(pad "1" smd rect
			(at -4.45008 0 90)
			(size 2.2098 4.4196)
			(layers "F.Cu" "F.Mask" "F.Paste")
			(net "P52V_FAN_7")
		)
		(pad "2" smd rect
			(at 4.45008 0 90)
			(size 2.2098 4.4196)
			(layers "F.Cu" "F.Mask" "F.Paste")
			(net "GND")
		)
	)
	(footprint ""
		(layer "F.Cu")
		(at 38.62705 -137.668)
		(property "Reference" "R5573"
			(at 0 0 0)
			(layer "F.SilkS")
			(hide yes)
			(effects
				(font
					(size 1.27 1.27)
				)
			)
		)
		(property "Value" ""
			(at 0 0 0)
			(layer "F.Fab")
			(effects
				(font
					(size 1.27 1.27)
				)
			)
		)
		(duplicate_pad_numbers_are_jumpers no)
		(fp_line
			(start -0.7874 -0.4064)
			(end 0.7874 -0.4064)
			(stroke
				(width 0.1524)
				(type default)
			)
			(layer "F.SilkS")
		)
		(fp_line
			(start -0.7874 0.4064)
			(end -0.7874 -0.4064)
			(stroke
				(width 0.1524)
				(type default)
			)
			(layer "F.SilkS")
		)
		(fp_line
			(start 0.7874 -0.4064)
			(end 0.7874 0.4064)
			(stroke
				(width 0.1524)
				(type default)
			)
			(layer "F.SilkS")
		)
		(fp_line
			(start 0.7874 0.4064)
			(end -0.7874 0.4064)
			(stroke
				(width 0.1524)
				(type default)
			)
			(layer "F.SilkS")
		)
		(fp_line
			(start -0.67945 -0.305054)
			(end -0.12065 -0.305054)
			(stroke
				(width 0.1)
				(type default)
			)
			(layer "F.Fab")
		)
		(fp_line
			(start -0.67945 0.3048)
			(end -0.67945 -0.305054)
			(stroke
				(width 0.1)
				(type default)
			)
			(layer "F.Fab")
		)
		(fp_line
			(start -0.12065 -0.305054)
			(end -0.12065 -0.2794)
			(stroke
				(width 0.1)
				(type default)
			)
			(layer "F.Fab")
		)
		(fp_line
			(start -0.12065 -0.2794)
			(end 0.12065 -0.2794)
			(stroke
				(width 0.1)
				(type default)
			)
			(layer "F.Fab")
		)
		(fp_line
			(start -0.12065 0.2794)
			(end -0.12065 0.3048)
			(stroke
				(width 0.1)
				(type default)
			)
			(layer "F.Fab")
		)
		(fp_line
			(start -0.12065 0.3048)
			(end -0.67945 0.3048)
			(stroke
				(width 0.1)
				(type default)
			)
			(layer "F.Fab")
		)
		(fp_line
			(start 0.120396 0.2794)
			(end -0.12065 0.2794)
			(stroke
				(width 0.1)
				(type default)
			)
			(layer "F.Fab")
		)
		(fp_line
			(start 0.120396 0.3048)
			(end 0.120396 0.2794)
			(stroke
				(width 0.1)
				(type default)
			)
			(layer "F.Fab")
		)
		(fp_line
			(start 0.12065 -0.3048)
			(end 0.67945 -0.3048)
			(stroke
				(width 0.1)
				(type default)
			)
			(layer "F.Fab")
		)
		(fp_line
			(start 0.12065 -0.2794)
			(end 0.12065 -0.3048)
			(stroke
				(width 0.1)
				(type default)
			)
			(layer "F.Fab")
		)
		(fp_line
			(start 0.67945 -0.3048)
			(end 0.67945 0.3048)
			(stroke
				(width 0.1)
				(type default)
			)
			(layer "F.Fab")
		)
		(fp_line
			(start 0.67945 0.3048)
			(end 0.120396 0.3048)
			(stroke
				(width 0.1)
				(type default)
			)
			(layer "F.Fab")
		)
		(pad "1" smd rect
			(at -0.40005 0 180)
			(size 0.4572 0.508)
			(layers "F.Cu" "F.Mask" "F.Paste")
			(net "FAN_0_PWM")
		)
		(pad "2" smd rect
			(at 0.40005 0 180)
			(size 0.4572 0.508)
			(layers "F.Cu" "F.Mask" "F.Paste")
			(net "FAN_0_PWM_R2")
		)
	)
	(footprint ""
		(layer "F.Cu")
		(at 6.477 -174.244)
		(property "Reference" "R4864"
			(at 0 0 0)
			(layer "F.SilkS")
			(hide yes)
			(effects
				(font
					(size 1.27 1.27)
				)
			)
		)
		(property "Value" ""
			(at 0 0 0)
			(layer "F.Fab")
			(effects
				(font
					(size 1.27 1.27)
				)
			)
		)
		(duplicate_pad_numbers_are_jumpers no)
		(fp_line
			(start -0.7874 -0.4064)
			(end 0.7874 -0.4064)
			(stroke
				(width 0.1524)
				(type default)
			)
			(layer "F.SilkS")
		)
		(fp_line
			(start -0.7874 0.4064)
			(end -0.7874 -0.4064)
			(stroke
				(width 0.1524)
				(type default)
			)
			(layer "F.SilkS")
		)
		(fp_line
			(start 0.7874 -0.4064)
			(end 0.7874 0.4064)
			(stroke
				(width 0.1524)
				(type default)
			)
			(layer "F.SilkS")
		)
		(fp_line
			(start 0.7874 0.4064)
			(end -0.7874 0.4064)
			(stroke
				(width 0.1524)
				(type default)
			)
			(layer "F.SilkS")
		)
		(fp_line
			(start -0.67945 -0.305054)
			(end -0.12065 -0.305054)
			(stroke
				(width 0.1)
				(type default)
			)
			(layer "F.Fab")
		)
		(fp_line
			(start -0.67945 0.3048)
			(end -0.67945 -0.305054)
			(stroke
				(width 0.1)
				(type default)
			)
			(layer "F.Fab")
		)
		(fp_line
			(start -0.12065 -0.305054)
			(end -0.12065 -0.2794)
			(stroke
				(width 0.1)
				(type default)
			)
			(layer "F.Fab")
		)
		(fp_line
			(start -0.12065 -0.2794)
			(end 0.12065 -0.2794)
			(stroke
				(width 0.1)
				(type default)
			)
			(layer "F.Fab")
		)
		(fp_line
			(start -0.12065 0.2794)
			(end -0.12065 0.3048)
			(stroke
				(width 0.1)
				(type default)
			)
			(layer "F.Fab")
		)
		(fp_line
			(start -0.12065 0.3048)
			(end -0.67945 0.3048)
			(stroke
				(width 0.1)
				(type default)
			)
			(layer "F.Fab")
		)
		(fp_line
			(start 0.120396 0.2794)
			(end -0.12065 0.2794)
			(stroke
				(width 0.1)
				(type default)
			)
			(layer "F.Fab")
		)
		(fp_line
			(start 0.120396 0.3048)
			(end 0.120396 0.2794)
			(stroke
				(width 0.1)
				(type default)
			)
			(layer "F.Fab")
		)
		(fp_line
			(start 0.12065 -0.3048)
			(end 0.67945 -0.3048)
			(stroke
				(width 0.1)
				(type default)
			)
			(layer "F.Fab")
		)
		(fp_line
			(start 0.12065 -0.2794)
			(end 0.12065 -0.3048)
			(stroke
				(width 0.1)
				(type default)
			)
			(layer "F.Fab")
		)
		(fp_line
			(start 0.67945 -0.3048)
			(end 0.67945 0.3048)
			(stroke
				(width 0.1)
				(type default)
			)
			(layer "F.Fab")
		)
		(fp_line
			(start 0.67945 0.3048)
			(end 0.120396 0.3048)
			(stroke
				(width 0.1)
				(type default)
			)
			(layer "F.Fab")
		)
		(pad "1" smd circle
			(at -0.40005 0)
			(size 0 0)
			(layers "F.Cu" "F.Mask" "F.Paste")
			(net "P3V3_AUX")
		)
		(pad "2" smd circle
			(at 0.40005 0)
			(size 0 0)
			(layers "F.Cu" "F.Mask" "F.Paste")
			(net "FAN_7_PRSNT_BUF_R_N")
		)
	)
)
